# SCM (Grand Teton) — schematic netlist excerpt (pin names and nets, part order shuffled) for the footprints in the layout excerpt that follows; sources: Cadence DE-HDL packaged netlist, KiCad conversion of 12092022_DA0F0TMDCD0_F0T_Management_Board_D_brd_V3_OCP.brd

C110  Q_CAP  1UF 25V 10% X6S  pkg C0402  page 16 : A = P3V3_AUX ; B = GND
R776  Q_RES  47K 1% CHIP  pkg 0402LF  page 15 : A = BATTERY_DETECT_R ; B = GND
C218  Q_CAP  1UF 25V 10% X6S  pkg C0402  page 41 : A = VCCIO5 ; B = GND

(kicad_pcb
	(version 20260206)
	(generator "pcbnew")
	(generator_version "10.0")
	(general
		(thickness 1.6)
		(legacy_teardrops no)
	)
	(paper "A4")
	(title_block
		(title "12092022_DA0F0TMDCD0_F0T_Management_Board_D_brd_V3_OCP.brd")
		(comment 1 "Grand Teton / footprints 811-813 of 1440")
	)
	(layers
		(0 "F.Cu" signal "TOP")
		(4 "In1.Cu" signal "GND")
		(6 "In2.Cu" signal "IN1")
		(8 "In3.Cu" signal "GND1")
		(10 "In4.Cu" signal "IN2")
		(12 "In5.Cu" signal "VCC")
		(14 "In6.Cu" signal "VCC1")
		(16 "In7.Cu" signal "IN3")
		(18 "In8.Cu" signal "GND2")
		(20 "In9.Cu" signal "IN4")
		(22 "In10.Cu" signal "GND3")
		(2 "B.Cu" signal "BOTTOM")
		(9 "F.Adhes" user "F.Adhesive")
		(11 "B.Adhes" user "B.Adhesive")
		(13 "F.Paste" user "Package Geometry/Pastemask Top")
		(15 "B.Paste" user "Package Geometry/Pastemask Bottom")
		(5 "F.SilkS" user "Ref Des/Silkscreen Top")
		(7 "B.SilkS" user "Ref Des/Silkscreen Bottom")
		(1 "F.Mask" user "Board Geometry/Soldermask Top")
		(3 "B.Mask" user "Board Geometry/Soldermask Bottom")
		(17 "Dwgs.User" user "User.Drawings")
		(19 "Cmts.User" user "User.Comments")
		(21 "Eco1.User" user "User.Eco1")
		(23 "Eco2.User" user "User.Eco2")
		(25 "Edge.Cuts" user "Board Geometry/Outline")
		(27 "Margin" user)
		(31 "F.CrtYd" user "Package Geometry/Place Bound Top")
		(29 "B.CrtYd" user "Package Geometry/Place Bound Bottom")
		(35 "F.Fab" user "Ref Des/Assembly Top")
		(33 "B.Fab" user "Ref Des/Assembly Bottom")
	)
	(footprint ""
		(layer "B.Cu")
		(at 47.846742 -73.957688 180)
		(property "Reference" "R776"
			(at 0 0 0)
			(layer "B.SilkS")
			(hide yes)
			(effects
				(font
					(size 1.27 1.27)
				)
				(justify mirror)
			)
		)
		(property "Value" ""
			(at 0 0 0)
			(layer "B.Fab")
			(effects
				(font
					(size 1.27 1.27)
				)
				(justify mirror)
			)
		)
		(duplicate_pad_numbers_are_jumpers no)
		(fp_line
			(start 0.7874 0.4064)
			(end 0.7874 -0.4064)
			(stroke
				(width 0.1524)
				(type default)
			)
			(layer "B.SilkS")
		)
		(fp_line
			(start 0.7874 -0.4064)
			(end -0.7874 -0.4064)
			(stroke
				(width 0.1524)
				(type default)
			)
			(layer "B.SilkS")
		)
		(fp_line
			(start -0.7874 0.4064)
			(end 0.7874 0.4064)
			(stroke
				(width 0.1524)
				(type default)
			)
			(layer "B.SilkS")
		)
		(fp_line
			(start -0.7874 -0.4064)
			(end -0.7874 0.4064)
			(stroke
				(width 0.1524)
				(type default)
			)
			(layer "B.SilkS")
		)
		(fp_line
			(start 0.67945 0.3048)
			(end 0.67945 -0.305054)
			(stroke
				(width 0.1)
				(type default)
			)
			(layer "B.Fab")
		)
		(fp_line
			(start 0.67945 -0.305054)
			(end 0.12065 -0.305054)
			(stroke
				(width 0.1)
				(type default)
			)
			(layer "B.Fab")
		)
		(fp_line
			(start 0.12065 0.3048)
			(end 0.67945 0.3048)
			(stroke
				(width 0.1)
				(type default)
			)
			(layer "B.Fab")
		)
		(fp_line
			(start 0.12065 0.2794)
			(end 0.12065 0.3048)
			(stroke
				(width 0.1)
				(type default)
			)
			(layer "B.Fab")
		)
		(fp_line
			(start 0.12065 -0.2794)
			(end -0.12065 -0.2794)
			(stroke
				(width 0.1)
				(type default)
			)
			(layer "B.Fab")
		)
		(fp_line
			(start 0.12065 -0.305054)
			(end 0.12065 -0.2794)
			(stroke
				(width 0.1)
				(type default)
			)
			(layer "B.Fab")
		)
		(fp_line
			(start -0.120396 0.3048)
			(end -0.120396 0.2794)
			(stroke
				(width 0.1)
				(type default)
			)
			(layer "B.Fab")
		)
		(fp_line
			(start -0.120396 0.2794)
			(end 0.12065 0.2794)
			(stroke
				(width 0.1)
				(type default)
			)
			(layer "B.Fab")
		)
		(fp_line
			(start -0.12065 -0.2794)
			(end -0.12065 -0.3048)
			(stroke
				(width 0.1)
				(type default)
			)
			(layer "B.Fab")
		)
		(fp_line
			(start -0.12065 -0.3048)
			(end -0.67945 -0.3048)
			(stroke
				(width 0.1)
				(type default)
			)
			(layer "B.Fab")
		)
		(fp_line
			(start -0.67945 0.3048)
			(end -0.120396 0.3048)
			(stroke
				(width 0.1)
				(type default)
			)
			(layer "B.Fab")
		)
		(fp_line
			(start -0.67945 -0.3048)
			(end -0.67945 0.3048)
			(stroke
				(width 0.1)
				(type default)
			)
			(layer "B.Fab")
		)
		(pad "1" smd circle
			(at 0.40005 0)
			(size 0 0)
			(layers "B.Cu" "B.Mask" "B.Paste")
			(net "BATTERY_DETECT_R")
		)
		(pad "2" smd circle
			(at -0.40005 0)
			(size 0 0)
			(layers "B.Cu" "B.Mask" "B.Paste")
			(net "GND")
		)
	)
	(footprint ""
		(layer "B.Cu")
		(at 53.337968 -43.761406 180)
		(property "Reference" "C110"
			(at 0 0 0)
			(layer "B.SilkS")
			(hide yes)
			(effects
				(font
					(size 1.27 1.27)
				)
				(justify mirror)
			)
		)
		(property "Value" ""
			(at 0 0 0)
			(layer "B.Fab")
			(effects
				(font
					(size 1.27 1.27)
				)
				(justify mirror)
			)
		)
		(duplicate_pad_numbers_are_jumpers no)
		(fp_line
			(start 0.7874 0.4064)
			(end 0.7874 -0.4064)
			(stroke
				(width 0.1524)
				(type default)
			)
			(layer "B.SilkS")
		)
		(fp_line
			(start 0.7874 -0.4064)
			(end -0.7874 -0.4064)
			(stroke
				(width 0.1524)
				(type default)
			)
			(layer "B.SilkS")
		)
		(fp_line
			(start -0.7874 0.4064)
			(end 0.7874 0.4064)
			(stroke
				(width 0.1524)
				(type default)
			)
			(layer "B.SilkS")
		)
		(fp_line
			(start -0.7874 -0.4064)
			(end -0.7874 0.4064)
			(stroke
				(width 0.1524)
				(type default)
			)
			(layer "B.SilkS")
		)
		(fp_line
			(start 0.67945 0.3048)
			(end 0.67945 -0.305054)
			(stroke
				(width 0.1)
				(type default)
			)
			(layer "B.Fab")
		)
		(fp_line
			(start 0.67945 -0.305054)
			(end 0.12065 -0.305054)
			(stroke
				(width 0.1)
				(type default)
			)
			(layer "B.Fab")
		)
		(fp_line
			(start 0.12065 0.3048)
			(end 0.67945 0.3048)
			(stroke
				(width 0.1)
				(type default)
			)
			(layer "B.Fab")
		)
		(fp_line
			(start 0.12065 0.2794)
			(end 0.12065 0.3048)
			(stroke
				(width 0.1)
				(type default)
			)
			(layer "B.Fab")
		)
		(fp_line
			(start 0.12065 -0.2794)
			(end -0.12065 -0.2794)
			(stroke
				(width 0.1)
				(type default)
			)
			(layer "B.Fab")
		)
		(fp_line
			(start 0.12065 -0.305054)
			(end 0.12065 -0.2794)
			(stroke
				(width 0.1)
				(type default)
			)
			(layer "B.Fab")
		)
		(fp_line
			(start -0.120396 0.3048)
			(end -0.120396 0.2794)
			(stroke
				(width 0.1)
				(type default)
			)
			(layer "B.Fab")
		)
		(fp_line
			(start -0.120396 0.2794)
			(end 0.12065 0.2794)
			(stroke
				(width 0.1)
				(type default)
			)
			(layer "B.Fab")
		)
		(fp_line
			(start -0.12065 -0.2794)
			(end -0.12065 -0.3048)
			(stroke
				(width 0.1)
				(type default)
			)
			(layer "B.Fab")
		)
		(fp_line
			(start -0.12065 -0.3048)
			(end -0.67945 -0.3048)
			(stroke
				(width 0.1)
				(type default)
			)
			(layer "B.Fab")
		)
		(fp_line
			(start -0.67945 0.3048)
			(end -0.120396 0.3048)
			(stroke
				(width 0.1)
				(type default)
			)
			(layer "B.Fab")
		)
		(fp_line
			(start -0.67945 -0.3048)
			(end -0.67945 0.3048)
			(stroke
				(width 0.1)
				(type default)
			)
			(layer "B.Fab")
		)
		(pad "1" smd circle
			(at 0.40005 0)
			(size 0 0)
			(layers "B.Cu" "B.Mask" "B.Paste")
			(net "P3V3_AUX")
		)
		(pad "2" smd circle
			(at -0.40005 0)
			(size 0 0)
			(layers "B.Cu" "B.Mask" "B.Paste")
			(net "GND")
		)
	)
	(footprint ""
		(layer "B.Cu")
		(at 26.259536 -89.98712 180)
		(property "Reference" "C218"
			(at 0 0 0)
			(layer "B.SilkS")
			(hide yes)
			(effects
				(font
					(size 1.27 1.27)
				)
				(justify mirror)
			)
		)
		(property "Value" ""
			(at 0 0 0)
			(layer "B.Fab")
			(effects
				(font
					(size 1.27 1.27)
				)
				(justify mirror)
			)
		)
		(duplicate_pad_numbers_are_jumpers no)
		(fp_line
			(start 0.69215 0.2921)
			(end 0.69215 -0.2921)
			(stroke
				(width 0.1524)
				(type default)
			)
			(layer "B.SilkS")
		)
		(fp_line
			(start 0.69215 -0.2921)
			(end -0.69215 -0.2921)
			(stroke
				(width 0.1524)
				(type default)
			)
			(layer "B.SilkS")
		)
		(fp_line
			(start -0.69215 0.2921)
			(end 0.69215 0.2921)
			(stroke
				(width 0.1524)
				(type default)
			)
			(layer "B.SilkS")
		)
		(fp_line
			(start -0.69215 -0.2921)
			(end -0.69215 0.2921)
			(stroke
				(width 0.1524)
				(type default)
			)
			(layer "B.SilkS")
		)
		(fp_line
			(start 0.51435 0.2794)
			(end 0.51435 -0.2794)
			(stroke
				(width 0.1)
				(type default)
			)
			(layer "B.Fab")
		)
		(fp_line
			(start 0.51435 -0.2794)
			(end -0.51435 -0.2794)
			(stroke
				(width 0.1)
				(type default)
			)
			(layer "B.Fab")
		)
		(fp_line
			(start -0.51435 0.2794)
			(end 0.51435 0.2794)
			(stroke
				(width 0.1)
				(type default)
			)
			(layer "B.Fab")
		)
		(fp_line
			(start -0.51435 -0.2794)
			(end -0.51435 0.2794)
			(stroke
				(width 0.1)
				(type default)
			)
			(layer "B.Fab")
		)
		(pad "1" smd circle
			(at 0.40005 0)
			(size 0 0)
			(layers "B.Cu" "B.Mask" "B.Paste")
			(net "VCCIO5")
		)
		(pad "2" smd circle
			(at -0.40005 0)
			(size 0 0)
			(layers "B.Cu" "B.Mask" "B.Paste")
			(net "GND")
		)
		(zone
			(layer "B.Cu")
			(hatch none 0.5)
			(connect_pads
				(clearance 0)
			)
			(min_thickness 0.25)
			(keepout
				(tracks not_allowed)
				(vias allowed)
				(pads allowed)
				(copperpour not_allowed)
				(footprints allowed)
			)
			(placement
				(enabled no)
				(sheetname "")
			)
			(fill
				(thermal_gap 0.5)
				(thermal_bridge_width 0.5)
				(island_removal_mode 0)
			)
			(polygon
				(pts
					(xy 26.069036 -90.07475) (xy 26.160476 -90.132916) (xy 26.359866 -90.132916) (xy 26.450036 -90.07475)
					(xy 26.450036 -89.89949) (xy 26.359866 -89.84107) (xy 26.160476 -89.84107) (xy 26.069036 -89.899236)
				)
			)
		)
	)
)
